(kicad_pcb
	(version 20221018)
	(generator pcbnew)
	(general
    (thickness 1.518)
  )
	(paper "A4")
	(title_block
    (title "Kria K26 Devboard")
    (date "2024-03-26")
    (rev "1.2.5")
    (comment 1 "www.antmicro.com")
    (comment 2 "Antmicro Ltd.")
		(comment 9 "footprints 68-76 of 660")
	)
	(layers
    (0 "F.Cu" mixed)
    (1 "In1.Cu" power)
    (2 "In2.Cu" mixed)
    (3 "In3.Cu" power)
    (4 "In4.Cu" mixed)
    (5 "In5.Cu" power)
    (6 "In6.Cu" mixed)
    (31 "B.Cu" power)
    (32 "B.Adhes" user "B.Adhesive")
    (33 "F.Adhes" user "F.Adhesive")
    (34 "B.Paste" user)
    (35 "F.Paste" user)
    (36 "B.SilkS" user "B.Silkscreen")
    (37 "F.SilkS" user "F.Silkscreen")
    (38 "B.Mask" user)
    (39 "F.Mask" user)
    (40 "Dwgs.User" user "User.Drawings")
    (41 "Cmts.User" user "User.Comments")
    (42 "Eco1.User" user "User.Eco1")
    (43 "Eco2.User" user "User.Eco2")
    (44 "Edge.Cuts" user)
    (45 "Margin" user)
    (46 "B.CrtYd" user "B.Courtyard")
    (47 "F.CrtYd" user "F.Courtyard")
    (48 "B.Fab" user)
    (49 "F.Fab" user)
  )
	(footprint "kria-k26-devboard-footprints:SOT-583" (layer "F.Cu")
    (at 136.983 136.374 -90)
    (property "Author" "Antmicro")
    (property "License" "Apache-2.0")
    (property "MPN" "TPS2116DRLR")
    (property "Manufacturer" "Texas Instruments")
    (property "Sheetfile" "sd-3-card.kicad_sch")
    (property "Sheetname" "SD 3.0 card")
    (property "ki_description" "Power switch")
    (property "ki_keywords" "SMT, SWITCH, IC, POWER, DRIVER")
    (attr smd)
    (fp_text reference "U6" (at -1.254 0.683) (layer "F.SilkS")
        (effects (font (size 0.7 0.7) (thickness 0.15)) (justify left bottom))
    )
    (fp_text value "TPS2116DRLR" (at 0 2.3 -90) (layer "F.Fab") hide
        (effects (font (size 0.7 0.7) (thickness 0.15)) (justify left bottom))
    )
    (fp_text user "Author: Antmicro" (at -0.06 5.025 -90) (layer "F.Fab") hide
        (effects (font (size 0.7 0.7) (thickness 0.15)) (justify left bottom))
    )
    (fp_text user "${REFERENCE}" (at -0.06 4.025 -90) (layer "F.Fab") hide
        (effects (font (size 0.7 0.7) (thickness 0.15)) (justify left bottom))
    )
    (fp_text user "License: Apache-2.0" (at -0.06 6.025 -90) (layer "F.Fab") hide
        (effects (font (size 0.7 0.7) (thickness 0.15)) (justify left bottom))
    )
    (fp_line (start -0.651 1.15) (end 0.651 1.15)
      (stroke (width 0.15) (type solid)) (layer "F.SilkS"))
    (fp_line (start -0.65 -1.15) (end 0.65 -1.15)
      (stroke (width 0.15) (type solid)) (layer "F.SilkS"))
    (fp_circle (center -0.9 -1.1) (end -0.85 -1.05)
      (stroke (width 0.15) (type solid)) (fill solid) (layer "F.SilkS"))
    (fp_rect (start -1.15 -1.3) (end 1.15 1.3)
      (stroke (width 0.05) (type solid)) (fill none) (layer "F.CrtYd"))
    (fp_line (start -0.651 -1.1005) (end 0.651 -1.1005)
      (stroke (width 0.15) (type solid)) (layer "F.Fab"))
    (fp_line (start -0.651 1.1005) (end -0.651 -1.1005)
      (stroke (width 0.15) (type solid)) (layer "F.Fab"))
    (fp_line (start -0.651 1.1005) (end 0.651 1.1005)
      (stroke (width 0.15) (type solid)) (layer "F.Fab"))
    (fp_line (start 0.651 1.1005) (end 0.651 -1.1005)
      (stroke (width 0.15) (type solid)) (layer "F.Fab"))
    (pad "1" smd roundrect (at -0.739 -0.7495 270) (size 0.670001 0.299999) (layers "F.Cu" "F.Paste" "F.Mask") (roundrect_rratio 0.25)
      (net 1 "GND") (pinfunction "GND") (pintype "power_in"))
    (pad "2" smd roundrect (at -0.739 -0.2505 270) (size 0.670001 0.299999) (layers "F.Cu" "F.Paste" "F.Mask") (roundrect_rratio 0.25)
      (net 104 "/SD 3.0 card/VCCB") (pinfunction "VOUT") (pintype "power_out"))
    (pad "3" smd roundrect (at -0.739 0.2495 270) (size 0.670001 0.299999) (layers "F.Cu" "F.Paste" "F.Mask") (roundrect_rratio 0.25)
      (net 17 "PS_1V8") (pinfunction "VIN1") (pintype "power_in"))
    (pad "4" smd roundrect (at -0.739 0.7495 270) (size 0.670001 0.299999) (layers "F.Cu" "F.Paste" "F.Mask") (roundrect_rratio 0.25)
      (net 109 "/SD 3.0 card/MIO39") (pinfunction "PR1") (pintype "input"))
    (pad "5" smd roundrect (at 0.74 0.7495 270) (size 0.670001 0.299999) (layers "F.Cu" "F.Paste" "F.Mask") (roundrect_rratio 0.25)
      (net 15 "PS_3V3") (pinfunction "MODE") (pintype "input"))
    (pad "6" smd roundrect (at 0.74 0.2495 270) (size 0.670001 0.299999) (layers "F.Cu" "F.Paste" "F.Mask") (roundrect_rratio 0.25)
      (net 15 "PS_3V3") (pinfunction "VIN2") (pintype "power_in"))
    (pad "7" smd roundrect (at 0.74 -0.2505 270) (size 0.670001 0.299999) (layers "F.Cu" "F.Paste" "F.Mask") (roundrect_rratio 0.25)
      (net 104 "/SD 3.0 card/VCCB") (pinfunction "VOUT") (pintype "passive"))
    (pad "8" smd roundrect (at 0.74 -0.7495 270) (size 0.670001 0.299999) (layers "F.Cu" "F.Paste" "F.Mask") (roundrect_rratio 0.25)
      (net 695 "Net-(U6-ST)") (pinfunction "ST") (pintype "output"))
  )
	(footprint "kria-k26-devboard-footprints:SOT-563" (layer "F.Cu")
    (at 144.35 142.1 90)
    (property "Author" "Antmicro")
    (property "License" "Apache-2.0")
    (property "MPN" "82400152")
    (property "Manufacturer" "Würth Elektronik")
    (property "Sheetfile" "debug.kicad_sch")
    (property "Sheetname" "Debug and JTAG")
    (property "ki_description" "Low Capacitance TVS Diode Array, 2 Channels, SOT563")
    (property "ki_keywords" "ESD Protection TVS High-speed USB")
    (attr smd)
    (fp_text reference "U37" (at 1.33 -1.17 180) (layer "F.SilkS")
        (effects (font (size 0.7 0.7) (thickness 0.15)) (justify left bottom))
    )
    (fp_text value "82400152" (at 0 2 90) (layer "F.Fab") hide
        (effects (font (size 0.7 0.7) (thickness 0.15)) (justify left bottom))
    )
    (fp_text user "Author: Antmicro" (at -1.299 6.124 90) (layer "F.Fab") hide
        (effects (font (size 0.7 0.7) (thickness 0.15)) (justify left bottom))
    )
    (fp_text user "${REFERENCE}" (at -1.299 7.323 90) (layer "F.Fab") hide
        (effects (font (size 0.7 0.7) (thickness 0.15)) (justify left bottom))
    )
    (fp_text user "License: Apache-2.0" (at -1.299 4.924 90) (layer "F.Fab") hide
        (effects (font (size 0.7 0.7) (thickness 0.15)) (justify left bottom))
    )
    (fp_line (start -0.778 0.776) (end -0.778 0.949)
      (stroke (width 0.15) (type solid)) (layer "F.SilkS"))
    (fp_line (start -0.778 0.949) (end -0.424 0.949)
      (stroke (width 0.15) (type solid)) (layer "F.SilkS"))
    (fp_line (start -0.499 -0.974) (end -0.724 -0.778)
      (stroke (width 0.15) (type solid)) (layer "F.SilkS"))
    (fp_line (start 0.776 -0.974) (end 0.526 -0.974)
      (stroke (width 0.15) (type solid)) (layer "F.SilkS"))
    (fp_line (start 0.776 -0.974) (end 0.776 -0.778)
      (stroke (width 0.15) (type solid)) (layer "F.SilkS"))
    (fp_line (start 0.776 0.776) (end 0.776 0.972)
      (stroke (width 0.15) (type solid)) (layer "F.SilkS"))
    (fp_line (start 0.776 0.972) (end 0.526 0.972)
      (stroke (width 0.15) (type solid)) (layer "F.SilkS"))
    (fp_circle (center -0.903 -0.999) (end -0.952 -0.95)
      (stroke (width 0.15) (type solid)) (fill solid) (layer "F.SilkS"))
    (fp_rect (start 1.19 -1.12) (end -1.2 1.1)
      (stroke (width 0.05) (type solid)) (fill none) (layer "F.CrtYd"))
    (fp_line (start -0.653 -0.678) (end -0.653 0.847)
      (stroke (width 0.15) (type solid)) (layer "F.Fab"))
    (fp_line (start -0.453 -0.849) (end -0.653 -0.678)
      (stroke (width 0.15) (type solid)) (layer "F.Fab"))
    (fp_line (start -0.453 -0.849) (end 0.651 -0.849)
      (stroke (width 0.15) (type solid)) (layer "F.Fab"))
    (fp_line (start 0.651 -0.849) (end 0.651 0.847)
      (stroke (width 0.15) (type solid)) (layer "F.Fab"))
    (fp_line (start 0.651 0.847) (end -0.653 0.847)
      (stroke (width 0.15) (type solid)) (layer "F.Fab"))
    (pad "1" smd roundrect (at -0.749 -0.499) (size 0.3 0.6) (layers "F.Cu" "F.Paste" "F.Mask") (roundrect_rratio 0.25)
      (net 355 "Net-(J8-D_{A}+)") (pintype "passive"))
    (pad "2" smd roundrect (at -0.749 0.001) (size 0.3 0.6) (layers "F.Cu" "F.Paste" "F.Mask") (roundrect_rratio 0.25)
      (net 1 "GND") (pintype "passive"))
    (pad "3" smd roundrect (at -0.749 0.497) (size 0.3 0.6) (layers "F.Cu" "F.Paste" "F.Mask") (roundrect_rratio 0.25)
      (net 356 "Net-(J8-D_{A}-)") (pintype "passive"))
    (pad "4" smd roundrect (at 0.747 0.497) (size 0.3 0.6) (layers "F.Cu" "F.Paste" "F.Mask") (roundrect_rratio 0.25)
      (net 223 "/Debug and JTAG/USBB_N") (pintype "passive"))
    (pad "5" smd roundrect (at 0.747 0.001) (size 0.3 0.6) (layers "F.Cu" "F.Paste" "F.Mask") (roundrect_rratio 0.25)
      (net 763 "unconnected-(U37-Pad5)") (pintype "passive+no_connect"))
    (pad "6" smd roundrect (at 0.747 -0.499) (size 0.3 0.6) (layers "F.Cu" "F.Paste" "F.Mask") (roundrect_rratio 0.25)
      (net 222 "/Debug and JTAG/USBB_P") (pintype "passive"))
  )
	(footprint "kria-k26-devboard-footprints:MP_Pad6mm_Drill3mm" (layer "F.Cu")
    (at 188.5 148.5)
    (property "Author" "Antmicro")
    (property "License" "Apache-2.0")
    (property "MPN" "")
    (property "Manufacturer" "")
    (property "Sheetfile" "k26_som.kicad_sch")
    (property "Sheetname" "Xilinx K26 SOM")
    (property "exclude_from_bom" "")
    (property "ki_description" "Mechanical part")
    (property "ki_keywords" "MECHANICAL")
    (attr through_hole exclude_from_bom)
    (fp_text reference "MP2" (at -0.178 4.025) (layer "F.SilkS") hide
        (effects (font (size 0.7 0.7) (thickness 0.15)) (justify left bottom))
    )
    (fp_text value "MP_Pad6mm_Drill3mm" (at -0.153 -4.153) (layer "F.Fab") hide
        (effects (font (size 0.7 0.7) (thickness 0.15)) (justify left bottom))
    )
    (fp_text user "License: Apache-2.0" (at -0.178 8.425) (layer "F.Fab") hide
        (effects (font (size 0.7 0.7) (thickness 0.15)) (justify left bottom))
    )
    (fp_text user "Author: Antmicro" (at -0.178 7.225) (layer "F.Fab") hide
        (effects (font (size 0.7 0.7) (thickness 0.15)) (justify left bottom))
    )
    (fp_text user "${REFERENCE}" (at -0.178 6.025) (layer "F.Fab") hide
        (effects (font (size 0.7 0.7) (thickness 0.15)) (justify left bottom))
    )
    (pad "1" thru_hole circle (at 0 0) (size 6 6) (drill 3.2) (layers "*.Cu" "*.Mask")
      (net 1 "GND") (pintype "passive"))
  )
	(footprint "kria-k26-devboard-footprints:MP_Pad6mm_Drill3mm" (layer "F.Cu")
    (at 77.5 148.5)
    (property "Author" "Antmicro")
    (property "License" "Apache-2.0")
    (property "MPN" "")
    (property "Manufacturer" "")
    (property "Sheetfile" "k26_som.kicad_sch")
    (property "Sheetname" "Xilinx K26 SOM")
    (property "exclude_from_bom" "")
    (property "ki_description" "Mechanical part")
    (property "ki_keywords" "MECHANICAL")
    (attr through_hole exclude_from_bom)
    (fp_text reference "MP1" (at -0.178 4.025) (layer "F.SilkS") hide
        (effects (font (size 0.7 0.7) (thickness 0.15)) (justify left bottom))
    )
    (fp_text value "MP_Pad6mm_Drill3mm" (at -0.153 -4.153) (layer "F.Fab") hide
        (effects (font (size 0.7 0.7) (thickness 0.15)) (justify left bottom))
    )
    (fp_text user "${REFERENCE}" (at -0.178 6.025) (layer "F.Fab") hide
        (effects (font (size 0.7 0.7) (thickness 0.15)) (justify left bottom))
    )
    (fp_text user "License: Apache-2.0" (at -0.178 8.425) (layer "F.Fab") hide
        (effects (font (size 0.7 0.7) (thickness 0.15)) (justify left bottom))
    )
    (fp_text user "Author: Antmicro" (at -0.178 7.225) (layer "F.Fab") hide
        (effects (font (size 0.7 0.7) (thickness 0.15)) (justify left bottom))
    )
    (pad "1" thru_hole circle (at 0 0) (size 6 6) (drill 3.2) (layers "*.Cu" "*.Mask")
      (net 1 "GND") (pintype "passive"))
  )
	(footprint "kria-k26-devboard-footprints:MP_Pad6mm_Drill3mm" (layer "F.Cu")
    (at 77.5 55.5)
    (property "Author" "Antmicro")
    (property "License" "Apache-2.0")
    (property "MPN" "")
    (property "Manufacturer" "")
    (property "Sheetfile" "k26_som.kicad_sch")
    (property "Sheetname" "Xilinx K26 SOM")
    (property "exclude_from_bom" "")
    (property "ki_description" "Mechanical part")
    (property "ki_keywords" "MECHANICAL")
    (attr through_hole exclude_from_bom)
    (fp_text reference "MP4" (at -1.18 2.54) (layer "F.SilkS") hide
        (effects (font (size 0.7 0.7) (thickness 0.15)) (justify left bottom))
    )
    (fp_text value "MP_Pad6mm_Drill3mm" (at -0.153 -4.153) (layer "F.Fab") hide
        (effects (font (size 0.7 0.7) (thickness 0.15)) (justify left bottom))
    )
    (fp_text user "${REFERENCE}" (at -0.178 6.025) (layer "F.Fab") hide
        (effects (font (size 0.7 0.7) (thickness 0.15)) (justify left bottom))
    )
    (fp_text user "Author: Antmicro" (at -0.178 7.225) (layer "F.Fab") hide
        (effects (font (size 0.7 0.7) (thickness 0.15)) (justify left bottom))
    )
    (fp_text user "License: Apache-2.0" (at -0.178 8.425) (layer "F.Fab") hide
        (effects (font (size 0.7 0.7) (thickness 0.15)) (justify left bottom))
    )
    (pad "1" thru_hole circle (at 0 0) (size 6 6) (drill 3.2) (layers "*.Cu" "*.Mask")
      (net 1 "GND") (pintype "passive"))
  )
	(footprint "kria-k26-devboard-footprints:MP_Pad6mm_Drill3mm" (layer "F.Cu")
    (at 188.5 55.5)
    (property "Author" "Antmicro")
    (property "License" "Apache-2.0")
    (property "MPN" "")
    (property "Manufacturer" "")
    (property "Sheetfile" "k26_som.kicad_sch")
    (property "Sheetname" "Xilinx K26 SOM")
    (property "exclude_from_bom" "")
    (property "ki_description" "Mechanical part")
    (property "ki_keywords" "MECHANICAL")
    (attr through_hole exclude_from_bom)
    (fp_text reference "MP3" (at -3.76 -2.56) (layer "F.SilkS") hide
        (effects (font (size 0.7 0.7) (thickness 0.15)) (justify left bottom))
    )
    (fp_text value "MP_Pad6mm_Drill3mm" (at -0.153 -4.153) (layer "F.Fab") hide
        (effects (font (size 0.7 0.7) (thickness 0.15)) (justify left bottom))
    )
    (fp_text user "${REFERENCE}" (at -0.178 6.025) (layer "F.Fab") hide
        (effects (font (size 0.7 0.7) (thickness 0.15)) (justify left bottom))
    )
    (fp_text user "Author: Antmicro" (at -0.178 7.225) (layer "F.Fab") hide
        (effects (font (size 0.7 0.7) (thickness 0.15)) (justify left bottom))
    )
    (fp_text user "License: Apache-2.0" (at -0.178 8.425) (layer "F.Fab") hide
        (effects (font (size 0.7 0.7) (thickness 0.15)) (justify left bottom))
    )
    (pad "1" thru_hole circle (at 0 0) (size 6 6) (drill 3.2) (layers "*.Cu" "*.Mask")
      (net 1 "GND") (pintype "passive"))
  )
	(footprint "kria-k26-devboard-footprints:C_0402_1005Metric" (layer "F.Cu")
    (at 123.075 130.3 90)
    (descr "Capacitor SMD 0402")
    (tags "capacitor SMD 0402")
    (property "Author" "Antmicro")
    (property "Dielectric" "X5R")
    (property "License" "Apache-2.0")
    (property "MPN" "GRM155R61H104KE14D")
    (property "Manufacturer" "Murata")
    (property "Sheetfile" "pcie-m2-key-e.kicad_sch")
    (property "Sheetname" "PCIE M2 key E ")
    (property "Val" "100n")
    (property "Voltage" "50V")
    (property "ki_description" " ")
    (attr smd)
    (fp_text reference "C235" (at -1.3 -0.605 90) (layer "F.SilkS")
        (effects (font (size 0.7 0.7) (thickness 0.15)) (justify left bottom))
    )
    (fp_text value "C_100n_0402" (at 0 1.4 90) (layer "F.Fab") hide
        (effects (font (size 0.7 0.7) (thickness 0.15)) (justify left bottom))
    )
    (fp_text user "Author: Antmicro" (at -0.932 4.17 90) (layer "F.Fab") hide
        (effects (font (size 0.7 0.7) (thickness 0.15)) (justify left bottom))
    )
    (fp_text user "${REFERENCE}" (at -0.932 3.168 90) (layer "F.Fab") hide
        (effects (font (size 0.7 0.7) (thickness 0.15)) (justify left bottom))
    )
    (fp_text user "License: Apache-2.0" (at -0.932 5.17 90) (layer "F.Fab") hide
        (effects (font (size 0.7 0.7) (thickness 0.15)) (justify left bottom))
    )
    (fp_rect (start -0.94 -0.47) (end 0.94 0.47)
      (stroke (width 0.05) (type solid)) (fill none) (layer "F.CrtYd"))
    (fp_rect (start -0.499 -0.249) (end 0.499 0.249)
      (stroke (width 0.15) (type solid)) (fill none) (layer "F.Fab"))
    (pad "1" smd roundrect (at -0.484 0 90) (size 0.59 0.64) (layers "F.Cu" "F.Paste" "F.Mask") (roundrect_rratio 0.25)
      (net 15 "PS_3V3") (pintype "passive"))
    (pad "2" smd roundrect (at 0.484 0 90) (size 0.59 0.64) (layers "F.Cu" "F.Paste" "F.Mask") (roundrect_rratio 0.25)
      (net 1 "GND") (pintype "passive"))
  )
	(footprint "kria-k26-devboard-footprints:C_0402_1005Metric" (layer "F.Cu")
    (at 122.9 113.75 -90)
    (descr "Capacitor SMD 0402")
    (tags "capacitor SMD 0402")
    (property "Author" "Antmicro")
    (property "Dielectric" "X5R")
    (property "License" "Apache-2.0")
    (property "MPN" "GRM155R61H104KE14D")
    (property "Manufacturer" "Murata")
    (property "Sheetfile" "pcie-m2-key-e.kicad_sch")
    (property "Sheetname" "PCIE M2 key E ")
    (property "Val" "100n")
    (property "Voltage" "50V")
    (property "ki_description" " ")
    (attr smd)
    (fp_text reference "C236" (at 1.38 0.57 -90) (layer "F.SilkS")
        (effects (font (size 0.7 0.7) (thickness 0.15)) (justify left bottom))
    )
    (fp_text value "C_100n_0402" (at 0 1.4 -90) (layer "F.Fab") hide
        (effects (font (size 0.7 0.7) (thickness 0.15)) (justify left bottom))
    )
    (fp_text user "Author: Antmicro" (at -0.932 4.17 -90) (layer "F.Fab") hide
        (effects (font (size 0.7 0.7) (thickness 0.15)) (justify left bottom))
    )
    (fp_text user "${REFERENCE}" (at -0.932 3.168 -90) (layer "F.Fab") hide
        (effects (font (size 0.7 0.7) (thickness 0.15)) (justify left bottom))
    )
    (fp_text user "License: Apache-2.0" (at -0.932 5.17 -90) (layer "F.Fab") hide
        (effects (font (size 0.7 0.7) (thickness 0.15)) (justify left bottom))
    )
    (fp_rect (start -0.94 -0.47) (end 0.94 0.47)
      (stroke (width 0.05) (type solid)) (fill none) (layer "F.CrtYd"))
    (fp_rect (start -0.499 -0.249) (end 0.499 0.249)
      (stroke (width 0.15) (type solid)) (fill none) (layer "F.Fab"))
    (pad "1" smd roundrect (at -0.484 0 270) (size 0.59 0.64) (layers "F.Cu" "F.Paste" "F.Mask") (roundrect_rratio 0.25)
      (net 15 "PS_3V3") (pintype "passive"))
    (pad "2" smd roundrect (at 0.484 0 270) (size 0.59 0.64) (layers "F.Cu" "F.Paste" "F.Mask") (roundrect_rratio 0.25)
      (net 1 "GND") (pintype "passive"))
  )
	(footprint "kria-k26-devboard-footprints:C_0603_1608Metric" (layer "F.Cu")
    (at 125 130.775)
    (descr "Capacitor SMD 0603")
    (tags "capacitor 0603")
    (property "Author" "Antmicro")
    (property "License" "Apache-2.0")
    (property "MPN" "GRM188R61A106KE69D")
    (property "Manufacturer" "Murata")
    (property "Sheetfile" "pcie-m2-key-e.kicad_sch")
    (property "Sheetname" "PCIE M2 key E ")
    (property "Val" "10u")
    (property "Voltage" "")
    (property "ki_description" " ")
    (attr smd)
    (fp_text reference "C237" (at -1.37 -0.565) (layer "F.SilkS")
        (effects (font (size 0.7 0.7) (thickness 0.15)) (justify left bottom))
    )
    (fp_text value "C_10u_0603" (at 0 1.6) (layer "F.Fab") hide
        (effects (font (size 0.7 0.7) (thickness 0.15)) (justify left bottom))
    )
    (fp_text user "License: Apache-2.0" (at -1.682 5.895) (layer "F.Fab") hide
        (effects (font (size 0.7 0.7) (thickness 0.15)) (justify left bottom))
    )
    (fp_text user "Author: Antmicro" (at -1.682 4.894) (layer "F.Fab") hide
        (effects (font (size 0.7 0.7) (thickness 0.15)) (justify left bottom))
    )
    (fp_text user "${REFERENCE}" (at -1.682 3.895) (layer "F.Fab") hide
        (effects (font (size 0.7 0.7) (thickness 0.15)) (justify left bottom))
    )
    (fp_line (start -0.3 -0.3) (end 0.3 -0.3)
      (stroke (width 0.15) (type solid)) (layer "F.SilkS"))
    (fp_line (start -0.3 0.3) (end 0.3 0.3)
      (stroke (width 0.15) (type solid)) (layer "F.SilkS"))
    (fp_rect (start -1.24 -0.7) (end 1.24 0.7)
      (stroke (width 0.05) (type solid)) (fill none) (layer "F.CrtYd"))
    (fp_rect (start -0.8 -0.4) (end 0.8 0.4)
      (stroke (width 0.15) (type solid)) (fill none) (layer "F.Fab"))
    (pad "1" smd roundrect (at -0.7 0) (size 0.6 0.8) (layers "F.Cu" "F.Paste" "F.Mask") (roundrect_rratio 0.2)
      (net 15 "PS_3V3") (pintype "passive"))
    (pad "2" smd roundrect (at 0.7 0) (size 0.6 0.8) (layers "F.Cu" "F.Paste" "F.Mask") (roundrect_rratio 0.2)
      (net 1 "GND") (pintype "passive"))
  )
)
